# T6G (Grand Teton) — schematic netlist excerpt (pin names and nets, part order shuffled) for the footprints in the layout excerpt that follows; sources: Cadence DE-HDL packaged netlist, KiCad conversion of 04192023_DAF0TMB3IC0_F0TG_MB_C_brd_V02_OCP.brd

C2577  Q_CAP  22UF 4V 20% X6S  pkg C0402  page 70 : A = PVDDCR_SOC_P0 ; B = GND
PR2512  Q_RES  1 1% CHIP  pkg 0402LF  page 266 : A = P12V_HSC_ADC_P ; B = P12V_HSC_SENSE2_R3_P

(kicad_pcb
	(version 20260206)
	(generator "pcbnew")
	(generator_version "10.0")
	(general
		(thickness 1.6)
		(legacy_teardrops no)
	)
	(paper "A4")
	(title_block
		(title "04192023_DAF0TMB3IC0_F0TG_MB_C_brd_V02_OCP.brd")
		(comment 1 "Grand Teton / footprints 6202-6203 of 8354")
	)
	(layers
		(0 "F.Cu" signal "TOP")
		(4 "In1.Cu" signal "GND")
		(6 "In2.Cu" signal "IN1")
		(8 "In3.Cu" signal "GND1")
		(10 "In4.Cu" signal "IN2")
		(12 "In5.Cu" signal "GND2")
		(14 "In6.Cu" signal "IN3")
		(16 "In7.Cu" signal "GND3")
		(18 "In8.Cu" signal "VCC")
		(20 "In9.Cu" signal "VCC1")
		(22 "In10.Cu" signal "GND4")
		(24 "In11.Cu" signal "IN4")
		(26 "In12.Cu" signal "GND5")
		(28 "In13.Cu" signal "IN5")
		(30 "In14.Cu" signal "GND6")
		(32 "In15.Cu" signal "IN6")
		(34 "In16.Cu" signal "GND7")
		(2 "B.Cu" signal "BOTTOM")
		(9 "F.Adhes" user "F.Adhesive")
		(11 "B.Adhes" user "B.Adhesive")
		(13 "F.Paste" user "Package Geometry/Pastemask Top")
		(15 "B.Paste" user "Package Geometry/Pastemask Bottom")
		(5 "F.SilkS" user "Ref Des/Silkscreen Top")
		(7 "B.SilkS" user "Ref Des/Silkscreen Bottom")
		(1 "F.Mask" user "Board Geometry/Soldermask Top")
		(3 "B.Mask" user "Board Geometry/Soldermask Bottom")
		(17 "Dwgs.User" user "User.Drawings")
		(19 "Cmts.User" user "User.Comments")
		(21 "Eco1.User" user "User.Eco1")
		(23 "Eco2.User" user "User.Eco2")
		(25 "Edge.Cuts" user "Board Geometry/Outline")
		(27 "Margin" user)
		(31 "F.CrtYd" user "Package Geometry/Place Bound Top")
		(29 "B.CrtYd" user "Package Geometry/Place Bound Bottom")
		(35 "F.Fab" user "Ref Des/Assembly Top")
		(33 "B.Fab" user "Ref Des/Assembly Bottom")
	)
	(footprint ""
		(layer "B.Cu")
		(at 369.62588 -259.729986)
		(property "Reference" "C2577"
			(at 0 0 0)
			(layer "B.SilkS")
			(hide yes)
			(effects
				(font
					(size 1.27 1.27)
				)
				(justify mirror)
			)
		)
		(property "Value" ""
			(at 0 0 0)
			(layer "B.Fab")
			(effects
				(font
					(size 1.27 1.27)
				)
				(justify mirror)
			)
		)
		(duplicate_pad_numbers_are_jumpers no)
		(fp_line
			(start -0.7874 -0.4064)
			(end -0.7874 0.4064)
			(stroke
				(width 0.1524)
				(type default)
			)
			(layer "B.SilkS")
		)
		(fp_line
			(start -0.7874 0.4064)
			(end 0.7874 0.4064)
			(stroke
				(width 0.1524)
				(type default)
			)
			(layer "B.SilkS")
		)
		(fp_line
			(start 0.7874 -0.4064)
			(end -0.7874 -0.4064)
			(stroke
				(width 0.1524)
				(type default)
			)
			(layer "B.SilkS")
		)
		(fp_line
			(start 0.7874 0.4064)
			(end 0.7874 -0.4064)
			(stroke
				(width 0.1524)
				(type default)
			)
			(layer "B.SilkS")
		)
		(fp_line
			(start -0.67945 -0.3048)
			(end -0.67945 0.3048)
			(stroke
				(width 0.1)
				(type default)
			)
			(layer "B.Fab")
		)
		(fp_line
			(start -0.67945 0.3048)
			(end -0.120396 0.3048)
			(stroke
				(width 0.1)
				(type default)
			)
			(layer "B.Fab")
		)
		(fp_line
			(start -0.12065 -0.3048)
			(end -0.67945 -0.3048)
			(stroke
				(width 0.1)
				(type default)
			)
			(layer "B.Fab")
		)
		(fp_line
			(start -0.12065 -0.2794)
			(end -0.12065 -0.3048)
			(stroke
				(width 0.1)
				(type default)
			)
			(layer "B.Fab")
		)
		(fp_line
			(start -0.120396 0.2794)
			(end 0.12065 0.2794)
			(stroke
				(width 0.1)
				(type default)
			)
			(layer "B.Fab")
		)
		(fp_line
			(start -0.120396 0.3048)
			(end -0.120396 0.2794)
			(stroke
				(width 0.1)
				(type default)
			)
			(layer "B.Fab")
		)
		(fp_line
			(start 0.12065 -0.305054)
			(end 0.12065 -0.2794)
			(stroke
				(width 0.1)
				(type default)
			)
			(layer "B.Fab")
		)
		(fp_line
			(start 0.12065 -0.2794)
			(end -0.12065 -0.2794)
			(stroke
				(width 0.1)
				(type default)
			)
			(layer "B.Fab")
		)
		(fp_line
			(start 0.12065 0.2794)
			(end 0.12065 0.3048)
			(stroke
				(width 0.1)
				(type default)
			)
			(layer "B.Fab")
		)
		(fp_line
			(start 0.12065 0.3048)
			(end 0.67945 0.3048)
			(stroke
				(width 0.1)
				(type default)
			)
			(layer "B.Fab")
		)
		(fp_line
			(start 0.67945 -0.305054)
			(end 0.12065 -0.305054)
			(stroke
				(width 0.1)
				(type default)
			)
			(layer "B.Fab")
		)
		(fp_line
			(start 0.67945 0.3048)
			(end 0.67945 -0.305054)
			(stroke
				(width 0.1)
				(type default)
			)
			(layer "B.Fab")
		)
		(pad "1" smd circle
			(at 0.40005 0 180)
			(size 0 0)
			(layers "B.Cu" "B.Mask" "B.Paste")
			(net "PVDDCR_SOC_P0")
		)
		(pad "2" smd circle
			(at -0.40005 0 180)
			(size 0 0)
			(layers "B.Cu" "B.Mask" "B.Paste")
			(net "GND")
		)
	)
	(footprint ""
		(layer "B.Cu")
		(at 208.461356 -380.206504)
		(property "Reference" "PR2512"
			(at 0 0 0)
			(layer "B.SilkS")
			(hide yes)
			(effects
				(font
					(size 1.27 1.27)
				)
				(justify mirror)
			)
		)
		(property "Value" ""
			(at 0 0 0)
			(layer "B.Fab")
			(effects
				(font
					(size 1.27 1.27)
				)
				(justify mirror)
			)
		)
		(duplicate_pad_numbers_are_jumpers no)
		(fp_line
			(start -0.7874 -0.4064)
			(end -0.7874 0.4064)
			(stroke
				(width 0.1524)
				(type default)
			)
			(layer "B.SilkS")
		)
		(fp_line
			(start -0.7874 0.4064)
			(end 0.7874 0.4064)
			(stroke
				(width 0.1524)
				(type default)
			)
			(layer "B.SilkS")
		)
		(fp_line
			(start 0.7874 -0.4064)
			(end -0.7874 -0.4064)
			(stroke
				(width 0.1524)
				(type default)
			)
			(layer "B.SilkS")
		)
		(fp_line
			(start 0.7874 0.4064)
			(end 0.7874 -0.4064)
			(stroke
				(width 0.1524)
				(type default)
			)
			(layer "B.SilkS")
		)
		(fp_line
			(start -0.67945 -0.3048)
			(end -0.67945 0.3048)
			(stroke
				(width 0.1)
				(type default)
			)
			(layer "B.Fab")
		)
		(fp_line
			(start -0.67945 0.3048)
			(end -0.120396 0.3048)
			(stroke
				(width 0.1)
				(type default)
			)
			(layer "B.Fab")
		)
		(fp_line
			(start -0.12065 -0.3048)
			(end -0.67945 -0.3048)
			(stroke
				(width 0.1)
				(type default)
			)
			(layer "B.Fab")
		)
		(fp_line
			(start -0.12065 -0.2794)
			(end -0.12065 -0.3048)
			(stroke
				(width 0.1)
				(type default)
			)
			(layer "B.Fab")
		)
		(fp_line
			(start -0.120396 0.2794)
			(end 0.12065 0.2794)
			(stroke
				(width 0.1)
				(type default)
			)
			(layer "B.Fab")
		)
		(fp_line
			(start -0.120396 0.3048)
			(end -0.120396 0.2794)
			(stroke
				(width 0.1)
				(type default)
			)
			(layer "B.Fab")
		)
		(fp_line
			(start 0.12065 -0.305054)
			(end 0.12065 -0.2794)
			(stroke
				(width 0.1)
				(type default)
			)
			(layer "B.Fab")
		)
		(fp_line
			(start 0.12065 -0.2794)
			(end -0.12065 -0.2794)
			(stroke
				(width 0.1)
				(type default)
			)
			(layer "B.Fab")
		)
		(fp_line
			(start 0.12065 0.2794)
			(end 0.12065 0.3048)
			(stroke
				(width 0.1)
				(type default)
			)
			(layer "B.Fab")
		)
		(fp_line
			(start 0.12065 0.3048)
			(end 0.67945 0.3048)
			(stroke
				(width 0.1)
				(type default)
			)
			(layer "B.Fab")
		)
		(fp_line
			(start 0.67945 -0.305054)
			(end 0.12065 -0.305054)
			(stroke
				(width 0.1)
				(type default)
			)
			(layer "B.Fab")
		)
		(fp_line
			(start 0.67945 0.3048)
			(end 0.67945 -0.305054)
			(stroke
				(width 0.1)
				(type default)
			)
			(layer "B.Fab")
		)
		(pad "1" smd circle
			(at 0.40005 0 180)
			(size 0 0)
			(layers "B.Cu" "B.Mask" "B.Paste")
			(net "P12V_HSC_ADC_P")
		)
		(pad "2" smd circle
			(at -0.40005 0 180)
			(size 0 0)
			(layers "B.Cu" "B.Mask" "B.Paste")
			(net "P12V_HSC_SENSE2_R3_P")
		)
	)
)
